# S9S_MB_2U (Grand Teton) — schematic netlist excerpt (pin names and nets, part order shuffled) for the footprints in the layout excerpt that follows; sources: Cadence DE-HDL packaged netlist, KiCad conversion of 03242023_DA0F0TMBIJ0_F0T_Motherboard_J_brd_V01_OCP.brd

Q83  MOSFET_NCH_DUAL  PJT138K IC  pkg SOT363XD  page 253
  S1  = GND
  G1  = PWRGD_PVCCIN_CPU0
  D2  = LED_PWRGD_PVCCIN_CPU1_D
  S2  = GND
  G2  = PWRGD_PVCCIN_CPU1
  D1  = LED_PWRGD_PVCCIN_CPU0_D

PR3994  Q_RES  0 5% CHIP  pkg 0402LF  page 303 : A = HSC_D_OC_4 ; B = HSC_D_OC_R

(kicad_pcb
	(version 20260206)
	(generator "pcbnew")
	(generator_version "10.0")
	(general
		(thickness 1.6)
		(legacy_teardrops no)
	)
	(paper "A4")
	(title_block
		(title "03242023_DA0F0TMBIJ0_F0T_Motherboard_J_brd_V01_OCP.brd")
		(comment 1 "Grand Teton / footprints 2821-2822 of 6105")
	)
	(layers
		(0 "F.Cu" signal "TOP")
		(4 "In1.Cu" signal "GND")
		(6 "In2.Cu" signal "IN1")
		(8 "In3.Cu" signal "GND1")
		(10 "In4.Cu" signal "IN2")
		(12 "In5.Cu" signal "GND2")
		(14 "In6.Cu" signal "IN3")
		(16 "In7.Cu" signal "GND3")
		(18 "In8.Cu" signal "VCC")
		(20 "In9.Cu" signal "VCC1")
		(22 "In10.Cu" signal "GND4")
		(24 "In11.Cu" signal "IN4")
		(26 "In12.Cu" signal "GND5")
		(28 "In13.Cu" signal "IN5")
		(30 "In14.Cu" signal "GND6")
		(32 "In15.Cu" signal "IN6")
		(34 "In16.Cu" signal "GND7")
		(2 "B.Cu" signal "BOTTOM")
		(9 "F.Adhes" user "F.Adhesive")
		(11 "B.Adhes" user "B.Adhesive")
		(13 "F.Paste" user "Package Geometry/Pastemask Top")
		(15 "B.Paste" user "Package Geometry/Pastemask Bottom")
		(5 "F.SilkS" user "Ref Des/Silkscreen Top")
		(7 "B.SilkS" user "Ref Des/Silkscreen Bottom")
		(1 "F.Mask" user "Board Geometry/Soldermask Top")
		(3 "B.Mask" user "Board Geometry/Soldermask Bottom")
		(17 "Dwgs.User" user "User.Drawings")
		(19 "Cmts.User" user "User.Comments")
		(21 "Eco1.User" user "User.Eco1")
		(23 "Eco2.User" user "User.Eco2")
		(25 "Edge.Cuts" user "Board Geometry/Outline")
		(27 "Margin" user)
		(31 "F.CrtYd" user "Package Geometry/Place Bound Top")
		(29 "B.CrtYd" user "Package Geometry/Place Bound Bottom")
		(35 "F.Fab" user "Ref Des/Assembly Top")
		(33 "B.Fab" user "Ref Des/Assembly Bottom")
	)
	(footprint ""
		(layer "F.Cu")
		(at 237.401608 -401.673822)
		(property "Reference" "PR3994"
			(at 0 0 0)
			(layer "F.SilkS")
			(hide yes)
			(effects
				(font
					(size 1.27 1.27)
				)
			)
		)
		(property "Value" ""
			(at 0 0 0)
			(layer "F.Fab")
			(effects
				(font
					(size 1.27 1.27)
				)
			)
		)
		(duplicate_pad_numbers_are_jumpers no)
		(fp_line
			(start -0.7874 -0.4064)
			(end 0.7874 -0.4064)
			(stroke
				(width 0.1524)
				(type default)
			)
			(layer "F.SilkS")
		)
		(fp_line
			(start -0.7874 0.4064)
			(end -0.7874 -0.4064)
			(stroke
				(width 0.1524)
				(type default)
			)
			(layer "F.SilkS")
		)
		(fp_line
			(start 0.7874 -0.4064)
			(end 0.7874 0.4064)
			(stroke
				(width 0.1524)
				(type default)
			)
			(layer "F.SilkS")
		)
		(fp_line
			(start 0.7874 0.4064)
			(end -0.7874 0.4064)
			(stroke
				(width 0.1524)
				(type default)
			)
			(layer "F.SilkS")
		)
		(fp_line
			(start -0.67945 -0.305054)
			(end -0.12065 -0.305054)
			(stroke
				(width 0.1)
				(type default)
			)
			(layer "F.Fab")
		)
		(fp_line
			(start -0.67945 0.3048)
			(end -0.67945 -0.305054)
			(stroke
				(width 0.1)
				(type default)
			)
			(layer "F.Fab")
		)
		(fp_line
			(start -0.12065 -0.305054)
			(end -0.12065 -0.2794)
			(stroke
				(width 0.1)
				(type default)
			)
			(layer "F.Fab")
		)
		(fp_line
			(start -0.12065 -0.2794)
			(end 0.12065 -0.2794)
			(stroke
				(width 0.1)
				(type default)
			)
			(layer "F.Fab")
		)
		(fp_line
			(start -0.12065 0.2794)
			(end -0.12065 0.3048)
			(stroke
				(width 0.1)
				(type default)
			)
			(layer "F.Fab")
		)
		(fp_line
			(start -0.12065 0.3048)
			(end -0.67945 0.3048)
			(stroke
				(width 0.1)
				(type default)
			)
			(layer "F.Fab")
		)
		(fp_line
			(start 0.120396 0.2794)
			(end -0.12065 0.2794)
			(stroke
				(width 0.1)
				(type default)
			)
			(layer "F.Fab")
		)
		(fp_line
			(start 0.120396 0.3048)
			(end 0.120396 0.2794)
			(stroke
				(width 0.1)
				(type default)
			)
			(layer "F.Fab")
		)
		(fp_line
			(start 0.12065 -0.3048)
			(end 0.67945 -0.3048)
			(stroke
				(width 0.1)
				(type default)
			)
			(layer "F.Fab")
		)
		(fp_line
			(start 0.12065 -0.2794)
			(end 0.12065 -0.3048)
			(stroke
				(width 0.1)
				(type default)
			)
			(layer "F.Fab")
		)
		(fp_line
			(start 0.67945 -0.3048)
			(end 0.67945 0.3048)
			(stroke
				(width 0.1)
				(type default)
			)
			(layer "F.Fab")
		)
		(fp_line
			(start 0.67945 0.3048)
			(end 0.120396 0.3048)
			(stroke
				(width 0.1)
				(type default)
			)
			(layer "F.Fab")
		)
		(pad "1" smd circle
			(at -0.40005 0)
			(size 0 0)
			(layers "F.Cu" "F.Mask" "F.Paste")
			(net "HSC_D_OC_4")
		)
		(pad "2" smd circle
			(at 0.40005 0)
			(size 0 0)
			(layers "F.Cu" "F.Mask" "F.Paste")
			(net "HSC_D_OC_R")
		)
	)
	(footprint ""
		(layer "F.Cu")
		(at 99.62388 -81.585308)
		(property "Reference" "Q83"
			(at 0.37592 -1.93675 0)
			(unlocked yes)
			(layer "F.SilkS")
			(effects
				(font
					(size 0.635 0.4064)
					(thickness 0.1524)
				)
			)
		)
		(property "Value" ""
			(at 0 0 0)
			(layer "F.Fab")
			(effects
				(font
					(size 1.27 1.27)
				)
			)
		)
		(duplicate_pad_numbers_are_jumpers no)
		(fp_line
			(start -1.332738 -1.100074)
			(end -0.4826 -1.100074)
			(stroke
				(width 0.1524)
				(type default)
			)
			(layer "F.SilkS")
		)
		(fp_line
			(start -1.332738 1.100074)
			(end -1.332738 -1.100074)
			(stroke
				(width 0.1524)
				(type default)
			)
			(layer "F.SilkS")
		)
		(fp_line
			(start -0.4826 -1.100074)
			(end 0 -0.541274)
			(stroke
				(width 0.1524)
				(type default)
			)
			(layer "F.SilkS")
		)
		(fp_line
			(start 0 -0.541274)
			(end 0.4826 -1.100074)
			(stroke
				(width 0.1524)
				(type default)
			)
			(layer "F.SilkS")
		)
		(fp_line
			(start 0.4826 -1.100074)
			(end 1.332738 -1.100074)
			(stroke
				(width 0.1524)
				(type default)
			)
			(layer "F.SilkS")
		)
		(fp_line
			(start 1.332738 -1.100074)
			(end 1.332738 1.100074)
			(stroke
				(width 0.1524)
				(type default)
			)
			(layer "F.SilkS")
		)
		(fp_line
			(start 1.332738 1.100074)
			(end -1.332738 1.100074)
			(stroke
				(width 0.1524)
				(type default)
			)
			(layer "F.SilkS")
		)
		(fp_poly
			(pts
				(xy -2.1082 -1.763014) (xy -1.406144 -1.411986) (xy -2.1082 -1.060958)
			)
			(stroke
				(width 0)
				(type default)
			)
			(fill yes)
			(layer "F.SilkS")
		)
		(fp_line
			(start -0.674878 -1.100074)
			(end 0.674878 -1.100074)
			(stroke
				(width 0.1)
				(type default)
			)
			(layer "F.Fab")
		)
		(fp_line
			(start -0.674878 1.100074)
			(end -0.674878 -1.100074)
			(stroke
				(width 0.1)
				(type default)
			)
			(layer "F.Fab")
		)
		(fp_line
			(start 0.674878 -1.100074)
			(end 0.674878 1.100074)
			(stroke
				(width 0.1)
				(type default)
			)
			(layer "F.Fab")
		)
		(fp_line
			(start 0.674878 1.100074)
			(end -0.674878 1.100074)
			(stroke
				(width 0.1)
				(type default)
			)
			(layer "F.Fab")
		)
		(fp_poly
			(pts
				(xy -2.2352 -0.298958) (xy -2.2352 -1.001014) (xy -1.533144 -0.649986)
			)
			(stroke
				(width 0)
				(type default)
			)
			(fill yes)
			(layer "F.Fab")
		)
		(pad "1" smd rect
			(at -0.94996 -0.649986 90)
			(size 0.4318 0.508)
			(layers "F.Cu" "F.Mask" "F.Paste")
			(net "GND")
		)
		(pad "2" smd rect
			(at -0.94996 0 90)
			(size 0.4318 0.508)
			(layers "F.Cu" "F.Mask" "F.Paste")
			(net "PWRGD_PVCCIN_CPU0")
		)
		(pad "3" smd rect
			(at -0.94996 0.649986 90)
			(size 0.4318 0.508)
			(layers "F.Cu" "F.Mask" "F.Paste")
			(net "LED_PWRGD_PVCCIN_CPU1_D")
		)
		(pad "4" smd rect
			(at 0.94996 0.649986 90)
			(size 0.4318 0.508)
			(layers "F.Cu" "F.Mask" "F.Paste")
			(net "GND")
		)
		(pad "5" smd rect
			(at 0.94996 0 90)
			(size 0.4318 0.508)
			(layers "F.Cu" "F.Mask" "F.Paste")
			(net "PWRGD_PVCCIN_CPU1")
		)
		(pad "6" smd rect
			(at 0.94996 -0.649986 90)
			(size 0.4318 0.508)
			(layers "F.Cu" "F.Mask" "F.Paste")
			(net "LED_PWRGD_PVCCIN_CPU0_D")
		)
	)
)
